# S9S_MB_2U (Grand Teton) — schematic netlist excerpt (pin names and nets, part order shuffled) for the footprints in the layout excerpt that follows; sources: Cadence DE-HDL packaged netlist, KiCad conversion of 03242023_DA0F0TMBIJ0_F0T_Motherboard_J_brd_V01_OCP.brd

J19  SCONN288_ADR50017P130CC  SCONN288_ADR50017-P130CC IO  pkg DDR288S_1-1VXB  page 100
  VIN_BULK0  = P12V_S3_AUX_CPU1_NVDIMM
  RFU0  = TP_CHB_CPU1_DIMM1_FRU_0
  VIN_MGMT  = P3V3_AUX
  HSCL  = I3C_SPD_DDRABCD_CPU1_LVC1_SCL_2
  HSDA  = I3C_SPD_DDRABCD_CPU1_LVC1_SDA
  VSS0  = GND
  DQ0_A  = M_B_CPU1_SA_DQ<0>
  VSS1  = GND
  DQ1_A  = M_B_CPU1_SA_DQ<1>
  VSS2  = GND
  DQS0_A_T  = M_B_CPU1_SA_DQS_DP<0>
  DQS0_A_C  = M_B_CPU1_SA_DQS_DN<0>
  VSS3  = GND
  DQ4_A  = M_B_CPU1_SA_DQ<4>
  VSS4  = GND
  DQ5_A  = M_B_CPU1_SA_DQ<5>
  VSS5  = GND
  DQ8_A  = M_B_CPU1_SA_DQ<8>
  VSS6  = GND
  DQ9_A  = M_B_CPU1_SA_DQ<9>
  VSS7  = GND
  DQS1_A_T  = M_B_CPU1_SA_DQS_DP<1>
  DQS1_A_C  = M_B_CPU1_SA_DQS_DN<1>
  VSS8  = GND
  DQ12_A  = M_B_CPU1_SA_DQ<12>
  VSS9  = GND
  DQ13_A  = M_B_CPU1_SA_DQ<13>
  VSS10  = GND
  DQ16_A  = M_B_CPU1_SA_DQ<16>
  VSS11  = GND
  DQ17_A  = M_B_CPU1_SA_DQ<17>
  VSS12  = GND
  DQS2_A_T  = M_B_CPU1_SA_DQS_DP<2>
  DQS2_A_C  = M_B_CPU1_SA_DQS_DN<2>
  VSS13  = GND
  DQ20_A  = M_B_CPU1_SA_DQ<20>
  VSS14  = GND
  DQ21_A  = M_B_CPU1_SA_DQ<21>
  VSS15  = GND
  DQ24_A  = M_B_CPU1_SA_DQ<24>
  VSS16  = GND
  DQ25_A  = M_B_CPU1_SA_DQ<25>
  VSS17  = GND
  DQS3_A_T  = M_B_CPU1_SA_DQS_DP<3>
  DQS3_A_C  = M_B_CPU1_SA_DQS_DN<3>
  VSS18  = GND
  DQ28_A  = M_B_CPU1_SA_DQ<28>
  VSS19  = GND
  DQ29_A  = M_B_CPU1_SA_DQ<29>
  VSS20  = GND
  CB0_A  = M_B_CPU1_SA_CB<0>
  VSS21  = GND
  CB1_A  = M_B_CPU1_SA_CB<1>
  VSS22  = GND
  DQS4_A_T  = M_B_CPU1_SA_DQS_DP<4>
  DQS4_A_C  = M_B_CPU1_SA_DQS_DN<4>
  VSS23  = GND
  CB4_A  = M_B_CPU1_SA_CB<4>
  VSS24  = GND
  CB5_A  = M_B_CPU1_SA_CB<5>
  VSS25  = GND
  ALERT_N  = M_B_CPU1_ALERT_N
  VSS26  = GND
  CS0_A_N  = M_B_CPU1_SA_CS_N<0>
  VSS27  = GND
  CA0_A  = M_B_CPU1_SA_CA<0>
  VSS28  = GND
  CA2_A  = M_B_CPU1_SA_CA<2>
  VSS29  = GND
  CA4_A  = M_B_CPU1_SA_CA<4>
  VSS30  = GND
  CA6_A  = M_B_CPU1_SA_CA<6>
  VSS31  = GND
  PAR_A  = M_B_CPU1_SA_PAR
  VSS32  = GND
  CA0_B  = M_B_CPU1_SB_CA<0>
  VSS33  = GND
  CA2_B  = M_B_CPU1_SB_CA<2>
  VSS34  = GND
  CA4_B  = M_B_CPU1_SB_CA<4>
  VSS35  = GND
  CA6_B  = M_B_CPU1_SB_CA<6>
  VSS36  = GND
  CS0_B_N  = M_B_CPU1_SB_CS_N<0>
  VSS37  = GND
  \lbd||rsp_a_n\  = M_B_CPU1_SA_RSP<0>
  \lbs||rsp_b_n\  = M_B_CPU1_SB_RSP<0>
  VSS38  = GND
  CB4_B  = M_B_CPU1_SB_CB<4>
  VSS39  = GND
  CB5_B  = M_B_CPU1_SB_CB<5>
  VSS40  = GND
  \dqs9_b_t||tdqs9_b_t||dbi4_b_n\  = M_B_CPU1_SB_DQS_DP<9>
  \dqs9_b_c||tdqs9_b_c\  = M_B_CPU1_SB_DQS_DN<9>
  VSS41  = GND
  CB0_B  = M_B_CPU1_SB_CB<0>
  VSS42  = GND
  CB1_B  = M_B_CPU1_SB_CB<1>
  VSS43  = GND
  DQ0_B  = M_B_CPU1_SB_DQ<0>
  VSS44  = GND
  DQ1_B  = M_B_CPU1_SB_DQ<1>
  VSS45  = GND
  DQS0_B_T  = M_B_CPU1_SB_DQS_DP<0>
  DQS0_B_C  = M_B_CPU1_SB_DQS_DN<0>
  VSS46  = GND
  DQ4_B  = M_B_CPU1_SB_DQ<4>
  VSS47  = GND
  DQ5_B  = M_B_CPU1_SB_DQ<5>
  VSS48  = GND
  DQ8_B  = M_B_CPU1_SB_DQ<8>
  VSS49  = GND
  DQ9_B  = M_B_CPU1_SB_DQ<9>
  VSS50  = GND
  DQS1_B_T  = M_B_CPU1_SB_DQS_DP<1>
  DQS1_B_C  = M_B_CPU1_SB_DQS_DN<1>
  VSS51  = GND
  DQ12_B  = M_B_CPU1_SB_DQ<12>
  VSS52  = GND
  DQ13_B  = M_B_CPU1_SB_DQ<13>
  VSS53  = GND
  DQ16_B  = M_B_CPU1_SB_DQ<16>
  VSS54  = GND
  DQ17_B  = M_B_CPU1_SB_DQ<17>
  VSS55  = GND
  DQS2_B_T  = M_B_CPU1_SB_DQS_DP<2>
  DQS2_B_C  = M_B_CPU1_SB_DQS_DN<2>
  VSS56  = GND
  DQ20_B  = M_B_CPU1_SB_DQ<20>
  VSS57  = GND
  DQ21_B  = M_B_CPU1_SB_DQ<21>
  VSS58  = GND
  DQ24_B  = M_B_CPU1_SB_DQ<24>
  VSS59  = GND
  DQ25_B  = M_B_CPU1_SB_DQ<25>
  VSS60  = GND
  DQS3_B_T  = M_B_CPU1_SB_DQS_DP<3>
  DQS3_B_C  = M_B_CPU1_SB_DQS_DN<3>
  VSS61  = GND
  DQ28_B  = M_B_CPU1_SB_DQ<28>
  VSS62  = GND
  DQ29_B  = M_B_CPU1_SB_DQ<29>
  VSS63  = GND
  RFU1  = TP_CHB_CPU1_DIMM1_FRU_1
  VIN_BULK1  = P12V_S3_AUX_CPU1_NVDIMM
  VIN_BULK2  = P12V_S3_AUX_CPU1_NVDIMM
  \pwr_good||fail_n\  = PWRGD_CHB_CPU1_DIMM1
  HSA  = PD_CHB_CPU1_DIMM1_SAA
  RFU2  = TP_CHB_CPU1_DIMM1_FRU_2
  RFU3  = TP_CHB_CPU1_DIMM1_FRU_3
  VSS64  = GND
  DQ2_A  = M_B_CPU1_SA_DQ<2>
  VSS65  = GND
  DQ3_A  = M_B_CPU1_SA_DQ<3>
  VSS66  = GND
  \dqs5_a_c||tdqs5_a_c||dqs5_a_t||tdqs5_a_t\  = M_B_CPU1_SA_DQS_DN<5>
  \dqs5_a_t||tdqs5_a_t\  = M_B_CPU1_SA_DQS_DP<5>
  VSS67  = GND
  DQ6_A  = M_B_CPU1_SA_DQ<6>
  VSS68  = GND
  DQ7_A  = M_B_CPU1_SA_DQ<7>
  VSS69  = GND
  DQ10_A  = M_B_CPU1_SA_DQ<10>
  VSS70  = GND
  DQ11_A  = M_B_CPU1_SA_DQ<11>
  VSS71  = GND
  \dqs6_a_c||tdqs6_a_c||dqs6_a_t||tdqs6_a_t\  = M_B_CPU1_SA_DQS_DN<6>
  \dqs6_a_t||tdqs6_a_t\  = M_B_CPU1_SA_DQS_DP<6>
  VSS72  = GND
  DQ14_A  = M_B_CPU1_SA_DQ<14>
  VSS73  = GND
  DQ15_A  = M_B_CPU1_SA_DQ<15>
  VSS74  = GND
  DQ18_A  = M_B_CPU1_SA_DQ<18>
  VSS75  = GND
  DQ19_A  = M_B_CPU1_SA_DQ<19>
  VSS76  = GND
  \dqs7_a_c||tdqs7_a_c\  = M_B_CPU1_SA_DQS_DN<7>
  \dqs7_a_t||tdqs7_a_t\  = M_B_CPU1_SA_DQS_DP<7>
  VSS77  = GND
  DQ22_A  = M_B_CPU1_SA_DQ<22>
  VSS78  = GND
  DQ23_A  = M_B_CPU1_SA_DQ<23>
  VSS79  = GND
  DQ26_A  = M_B_CPU1_SA_DQ<26>
  VSS80  = GND
  DQ27_A  = M_B_CPU1_SA_DQ<27>
  VSS81  = GND
  \dqs8_a_c||tdqs8_a_c\  = M_B_CPU1_SA_DQS_DN<8>
  \dqs8_a_t||tdqs8_a_t\  = M_B_CPU1_SA_DQS_DP<8>
  VSS82  = GND
  DQ30_A  = M_B_CPU1_SA_DQ<30>
  VSS83  = GND
  DQ31_A  = M_B_CPU1_SA_DQ<31>
  VSS84  = GND
  CB2_A  = M_B_CPU1_SA_CB<2>
  VSS85  = GND
  CB3_A  = M_B_CPU1_SA_CB<3>
  VSS86  = GND
  \dqs9_a_c||tdqs9_a_c\  = M_B_CPU1_SA_DQS_DN<9>
  \dqs9_a_t||tdqs9_a_t\  = M_B_CPU1_SA_DQS_DP<9>
  VSS87  = GND
  CB6_A  = M_B_CPU1_SA_CB<6>
  VSS88  = GND
  CB7_A  = M_B_CPU1_SA_CB<7>
  VSS89  = GND
  RESET_N  = RST_M_AB_CPU1_FPGA_N
  VSS90  = GND
  CS1_A_N  = M_B_CPU1_SA_CS_N<1>
  VSS91  = GND
  CA1_A  = M_B_CPU1_SA_CA<1>
  VSS92  = GND
  CA3_A  = M_B_CPU1_SA_CA<3>
  VSS93  = GND
  CA5_A  = M_B_CPU1_SA_CA<5>
  VSS94  = GND
  CK_T  = M_B_CPU1_CLK_DP<0>
  CK_C  = M_B_CPU1_CLK_DN<0>
  VSS95  = GND
  RFU4  = TP_CHB_CPU1_DIMM1_FRU_4
  CA1_B  = M_B_CPU1_SB_CA<1>
  VSS96  = GND
  CA3_B  = M_B_CPU1_SB_CA<3>
  VSS97  = GND
  CA5_B  = M_B_CPU1_SB_CA<5>
  VSS98  = GND
  PAR_B  = M_B_CPU1_SB_PAR
  VSS99  = GND
  CS1_B_N  = M_B_CPU1_SB_CS_N<1>
  VSS100  = GND
  RFU5  = TP_CHB_CPU1_DIMM1_FRU_5
  RFU6  = TP_CHB_CPU1_DIMM1_FRU_6
  VSS101  = GND
  CB6_B  = M_B_CPU1_SB_CB<6>
  VSS102  = GND
  CB7_B  = M_B_CPU1_SB_CB<7>
  VSS103  = GND
  DQS4_B_C  = M_B_CPU1_SB_DQS_DN<4>
  DQS4_B_T  = M_B_CPU1_SB_DQS_DP<4>
  VSS104  = GND
  CB2_B  = M_B_CPU1_SB_CB<2>
  VSS105  = GND
  CB3_B  = M_B_CPU1_SB_CB<3>
  VSS106  = GND
  DQ2_B  = M_B_CPU1_SB_DQ<2>
  VSS107  = GND
  DQ3_B  = M_B_CPU1_SB_DQ<3>
  VSS108  = GND
  \dqs5_b_c||tdqs5_b_c\  = M_B_CPU1_SB_DQS_DN<5>
  \dqs5_b_t||tdqs5_b_t\  = M_B_CPU1_SB_DQS_DP<5>
  VSS109  = GND
  DQ6_B  = M_B_CPU1_SB_DQ<6>
  VSS110  = GND
  DQ7_B  = M_B_CPU1_SB_DQ<7>
  VSS111  = GND
  DQ10_B  = M_B_CPU1_SB_DQ<10>
  VSS112  = GND
  DQ11_B  = M_B_CPU1_SB_DQ<11>
  VSS113  = GND
  \dqs6_b_c||tdqs6_b_c\  = M_B_CPU1_SB_DQS_DN<6>
  \dqs6_b_t||tdqs6_b_t\  = M_B_CPU1_SB_DQS_DP<6>
  VSS114  = GND
  DQ14_B  = M_B_CPU1_SB_DQ<14>
  VSS115  = GND
  DQ15_B  = M_B_CPU1_SB_DQ<15>
  VSS116  = GND
  DQ18_B  = M_B_CPU1_SB_DQ<18>
  VSS117  = GND
  DQ19_B  = M_B_CPU1_SB_DQ<19>
  VSS118  = GND
  \dqs7_b_c||tdqs7_b_c\  = M_B_CPU1_SB_DQS_DN<7>
  \dqs7_b_t||tdqs7_b_t\  = M_B_CPU1_SB_DQS_DP<7>
  VSS119  = GND
  DQ22_B  = M_B_CPU1_SB_DQ<22>
  VSS120  = GND
  DQ23_B  = M_B_CPU1_SB_DQ<23>
  VSS121  = GND
  DQ26_B  = M_B_CPU1_SB_DQ<26>
  VSS122  = GND
  DQ27_B  = M_B_CPU1_SB_DQ<27>
  VSS123  = GND
  \dqs8_b_c||tdqs8_b_c\  = M_B_CPU1_SB_DQS_DN<8>
  \dqs8_b_t||tdqs8_b_t\  = M_B_CPU1_SB_DQS_DP<8>
  VSS124  = GND
  DQ30_B  = M_B_CPU1_SB_DQ<30>
  VSS125  = GND
  DQ31_B  = M_B_CPU1_SB_DQ<31>
  VSS126  = GND
  G1  = GND
  G2  = GND
  G3  = GND

(kicad_pcb
	(version 20260206)
	(generator "pcbnew")
	(generator_version "10.0")
	(general
		(thickness 1.6)
		(legacy_teardrops no)
	)
	(paper "A4")
	(title_block
		(title "03242023_DA0F0TMBIJ0_F0T_Motherboard_J_brd_V01_OCP.brd")
		(comment 1 "Grand Teton / footprint 2188 of 6105 (J19), pads 1-45 of 291")
	)
	(layers
		(0 "F.Cu" signal "TOP")
		(4 "In1.Cu" signal "GND")
		(6 "In2.Cu" signal "IN1")
		(8 "In3.Cu" signal "GND1")
		(10 "In4.Cu" signal "IN2")
		(12 "In5.Cu" signal "GND2")
		(14 "In6.Cu" signal "IN3")
		(16 "In7.Cu" signal "GND3")
		(18 "In8.Cu" signal "VCC")
		(20 "In9.Cu" signal "VCC1")
		(22 "In10.Cu" signal "GND4")
		(24 "In11.Cu" signal "IN4")
		(26 "In12.Cu" signal "GND5")
		(28 "In13.Cu" signal "IN5")
		(30 "In14.Cu" signal "GND6")
		(32 "In15.Cu" signal "IN6")
		(34 "In16.Cu" signal "GND7")
		(2 "B.Cu" signal "BOTTOM")
		(9 "F.Adhes" user "F.Adhesive")
		(11 "B.Adhes" user "B.Adhesive")
		(13 "F.Paste" user "Package Geometry/Pastemask Top")
		(15 "B.Paste" user "Package Geometry/Pastemask Bottom")
		(5 "F.SilkS" user "Ref Des/Silkscreen Top")
		(7 "B.SilkS" user "Ref Des/Silkscreen Bottom")
		(1 "F.Mask" user "Board Geometry/Soldermask Top")
		(3 "B.Mask" user "Board Geometry/Soldermask Bottom")
		(17 "Dwgs.User" user "User.Drawings")
		(19 "Cmts.User" user "User.Comments")
		(21 "Eco1.User" user "User.Eco1")
		(23 "Eco2.User" user "User.Eco2")
		(25 "Edge.Cuts" user "Board Geometry/Outline")
		(27 "Margin" user)
		(31 "F.CrtYd" user "Package Geometry/Place Bound Top")
		(29 "B.CrtYd" user "Package Geometry/Place Bound Bottom")
		(35 "F.Fab" user "Ref Des/Assembly Top")
		(33 "B.Fab" user "Ref Des/Assembly Bottom")
	)
	(footprint ""
		(layer "F.Cu")
		(at 40.36568 -258.091686)
		(property "Reference" "J19"
			(at -5.21716 -81.970372 0)
			(unlocked yes)
			(layer "F.SilkS")
			(effects
				(font
					(size 0.7874 0.5842)
					(thickness 0.1524)
				)
				(justify left)
			)
		)
		(property "Value" ""
			(at 0 0 0)
			(layer "F.Fab")
			(effects
				(font
					(size 1.27 1.27)
				)
			)
		)
		(duplicate_pad_numbers_are_jumpers no)
		(pad "1" smd rect
			(at -2.050034 -63.324994 270)
			(size 0.519938 1.4986)
			(layers "F.Cu" "F.Mask" "F.Paste")
			(net "P12V_S3_AUX_CPU1_NVDIMM")
		)
		(pad "2" smd rect
			(at -2.050034 -62.47511 270)
			(size 0.519938 1.4986)
			(layers "F.Cu" "F.Mask" "F.Paste")
			(net "TP_CHB_CPU1_DIMM1_FRU_0")
		)
		(pad "3" smd rect
			(at -2.050034 -61.624972 270)
			(size 0.519938 1.4986)
			(layers "F.Cu" "F.Mask" "F.Paste")
			(net "P3V3_AUX")
		)
		(pad "4" smd rect
			(at -2.050034 -60.775088 270)
			(size 0.519938 1.4986)
			(layers "F.Cu" "F.Mask" "F.Paste")
			(net "I3C_SPD_DDRABCD_CPU1_LVC1_SCL_2")
		)
		(pad "5" smd rect
			(at -2.050034 -59.92495 270)
			(size 0.519938 1.4986)
			(layers "F.Cu" "F.Mask" "F.Paste")
			(net "I3C_SPD_DDRABCD_CPU1_LVC1_SDA")
		)
		(pad "6" smd rect
			(at -2.050034 -59.075066 270)
			(size 0.519938 1.4986)
			(layers "F.Cu" "F.Mask" "F.Paste")
			(net "GND")
		)
		(pad "7" smd rect
			(at -2.050034 -58.224928 270)
			(size 0.519938 1.4986)
			(layers "F.Cu" "F.Mask" "F.Paste")
			(net "M_B_CPU1_SA_DQ<0>")
		)
		(pad "8" smd rect
			(at -2.050034 -57.375044 270)
			(size 0.519938 1.4986)
			(layers "F.Cu" "F.Mask" "F.Paste")
			(net "GND")
		)
		(pad "9" smd rect
			(at -2.050034 -56.524906 270)
			(size 0.519938 1.4986)
			(layers "F.Cu" "F.Mask" "F.Paste")
			(net "M_B_CPU1_SA_DQ<1>")
		)
		(pad "10" smd rect
			(at -2.050034 -55.675022 270)
			(size 0.519938 1.4986)
			(layers "F.Cu" "F.Mask" "F.Paste")
			(net "GND")
		)
		(pad "11" smd rect
			(at -2.050034 -54.824884 270)
			(size 0.519938 1.4986)
			(layers "F.Cu" "F.Mask" "F.Paste")
			(net "M_B_CPU1_SA_DQS_DP<0>")
		)
		(pad "12" smd rect
			(at -2.050034 -53.975 270)
			(size 0.519938 1.4986)
			(layers "F.Cu" "F.Mask" "F.Paste")
			(net "M_B_CPU1_SA_DQS_DN<0>")
		)
		(pad "13" smd rect
			(at -2.050034 -53.125116 270)
			(size 0.519938 1.4986)
			(layers "F.Cu" "F.Mask" "F.Paste")
			(net "GND")
		)
		(pad "14" smd rect
			(at -2.050034 -52.274978 270)
			(size 0.519938 1.4986)
			(layers "F.Cu" "F.Mask" "F.Paste")
			(net "M_B_CPU1_SA_DQ<4>")
		)
		(pad "15" smd rect
			(at -2.050034 -51.425094 270)
			(size 0.519938 1.4986)
			(layers "F.Cu" "F.Mask" "F.Paste")
			(net "GND")
		)
		(pad "16" smd rect
			(at -2.050034 -50.574956 270)
			(size 0.519938 1.4986)
			(layers "F.Cu" "F.Mask" "F.Paste")
			(net "M_B_CPU1_SA_DQ<5>")
		)
		(pad "17" smd rect
			(at -2.050034 -49.725072 270)
			(size 0.519938 1.4986)
			(layers "F.Cu" "F.Mask" "F.Paste")
			(net "GND")
		)
		(pad "18" smd rect
			(at -2.050034 -48.874934 270)
			(size 0.519938 1.4986)
			(layers "F.Cu" "F.Mask" "F.Paste")
			(net "M_B_CPU1_SA_DQ<8>")
		)
		(pad "19" smd rect
			(at -2.050034 -48.02505 270)
			(size 0.519938 1.4986)
			(layers "F.Cu" "F.Mask" "F.Paste")
			(net "GND")
		)
		(pad "20" smd rect
			(at -2.050034 -47.174912 270)
			(size 0.519938 1.4986)
			(layers "F.Cu" "F.Mask" "F.Paste")
			(net "M_B_CPU1_SA_DQ<9>")
		)
		(pad "21" smd rect
			(at -2.050034 -46.325028 270)
			(size 0.519938 1.4986)
			(layers "F.Cu" "F.Mask" "F.Paste")
			(net "GND")
		)
		(pad "22" smd rect
			(at -2.050034 -45.47489 270)
			(size 0.519938 1.4986)
			(layers "F.Cu" "F.Mask" "F.Paste")
			(net "M_B_CPU1_SA_DQS_DP<1>")
		)
		(pad "23" smd rect
			(at -2.050034 -44.625006 270)
			(size 0.519938 1.4986)
			(layers "F.Cu" "F.Mask" "F.Paste")
			(net "M_B_CPU1_SA_DQS_DN<1>")
		)
		(pad "24" smd rect
			(at -2.050034 -43.775122 270)
			(size 0.519938 1.4986)
			(layers "F.Cu" "F.Mask" "F.Paste")
			(net "GND")
		)
		(pad "25" smd rect
			(at -2.050034 -42.924984 270)
			(size 0.519938 1.4986)
			(layers "F.Cu" "F.Mask" "F.Paste")
			(net "M_B_CPU1_SA_DQ<12>")
		)
		(pad "26" smd rect
			(at -2.050034 -42.0751 270)
			(size 0.519938 1.4986)
			(layers "F.Cu" "F.Mask" "F.Paste")
			(net "GND")
		)
		(pad "27" smd rect
			(at -2.050034 -41.224962 270)
			(size 0.519938 1.4986)
			(layers "F.Cu" "F.Mask" "F.Paste")
			(net "M_B_CPU1_SA_DQ<13>")
		)
		(pad "28" smd rect
			(at -2.050034 -40.375078 270)
			(size 0.519938 1.4986)
			(layers "F.Cu" "F.Mask" "F.Paste")
			(net "GND")
		)
		(pad "29" smd rect
			(at -2.050034 -39.52494 270)
			(size 0.519938 1.4986)
			(layers "F.Cu" "F.Mask" "F.Paste")
			(net "M_B_CPU1_SA_DQ<16>")
		)
		(pad "30" smd rect
			(at -2.050034 -38.675056 270)
			(size 0.519938 1.4986)
			(layers "F.Cu" "F.Mask" "F.Paste")
			(net "GND")
		)
		(pad "31" smd rect
			(at -2.050034 -37.824918 270)
			(size 0.519938 1.4986)
			(layers "F.Cu" "F.Mask" "F.Paste")
			(net "M_B_CPU1_SA_DQ<17>")
		)
		(pad "32" smd rect
			(at -2.050034 -36.975034 270)
			(size 0.519938 1.4986)
			(layers "F.Cu" "F.Mask" "F.Paste")
			(net "GND")
		)
		(pad "33" smd rect
			(at -2.050034 -36.124896 270)
			(size 0.519938 1.4986)
			(layers "F.Cu" "F.Mask" "F.Paste")
			(net "M_B_CPU1_SA_DQS_DP<2>")
		)
		(pad "34" smd rect
			(at -2.050034 -35.275012 270)
			(size 0.519938 1.4986)
			(layers "F.Cu" "F.Mask" "F.Paste")
			(net "M_B_CPU1_SA_DQS_DN<2>")
		)
		(pad "35" smd rect
			(at -2.050034 -34.425128 270)
			(size 0.519938 1.4986)
			(layers "F.Cu" "F.Mask" "F.Paste")
			(net "GND")
		)
		(pad "36" smd rect
			(at -2.050034 -33.57499 270)
			(size 0.519938 1.4986)
			(layers "F.Cu" "F.Mask" "F.Paste")
			(net "M_B_CPU1_SA_DQ<20>")
		)
		(pad "37" smd rect
			(at -2.050034 -32.725106 270)
			(size 0.519938 1.4986)
			(layers "F.Cu" "F.Mask" "F.Paste")
			(net "GND")
		)
		(pad "38" smd rect
			(at -2.050034 -31.874968 270)
			(size 0.519938 1.4986)
			(layers "F.Cu" "F.Mask" "F.Paste")
			(net "M_B_CPU1_SA_DQ<21>")
		)
		(pad "39" smd rect
			(at -2.050034 -31.025084 270)
			(size 0.519938 1.4986)
			(layers "F.Cu" "F.Mask" "F.Paste")
			(net "GND")
		)
		(pad "40" smd rect
			(at -2.050034 -30.174946 270)
			(size 0.519938 1.4986)
			(layers "F.Cu" "F.Mask" "F.Paste")
			(net "M_B_CPU1_SA_DQ<24>")
		)
		(pad "41" smd rect
			(at -2.050034 -29.325062 270)
			(size 0.519938 1.4986)
			(layers "F.Cu" "F.Mask" "F.Paste")
			(net "GND")
		)
		(pad "42" smd rect
			(at -2.050034 -28.474924 270)
			(size 0.519938 1.4986)
			(layers "F.Cu" "F.Mask" "F.Paste")
			(net "M_B_CPU1_SA_DQ<25>")
		)
		(pad "43" smd rect
			(at -2.050034 -27.62504 270)
			(size 0.519938 1.4986)
			(layers "F.Cu" "F.Mask" "F.Paste")
			(net "GND")
		)
		(pad "44" smd rect
			(at -2.050034 -26.774902 270)
			(size 0.519938 1.4986)
			(layers "F.Cu" "F.Mask" "F.Paste")
			(net "M_B_CPU1_SA_DQS_DP<3>")
		)
		(pad "45" smd rect
			(at -2.050034 -25.925018 270)
			(size 0.519938 1.4986)
			(layers "F.Cu" "F.Mask" "F.Paste")
			(net "M_B_CPU1_SA_DQS_DN<3>")
		)
	)
)
